(kicad_pcb
	(version 20241229)
	(generator "pcbnew")
	(generator_version "9.0")
	(general
		(thickness 1.711)
		(legacy_teardrops no)
	)
	(paper "A4")
	(title_block
		(title "Antmicro Baseboard for Jetson AGX Thor")
		(date "2026-02-18")
		(rev "1.1.0")
		(company "Antmicro Ltd")
		(comment 1 "www.antmicro.com")
		(comment 9 "footprints 887-892 of 1170")
	)
	(layers
		(0 "F.Cu" signal)
		(4 "In1.Cu" signal)
		(6 "In2.Cu" signal)
		(8 "In3.Cu" signal)
		(10 "In4.Cu" jumper)
		(12 "In5.Cu" signal)
		(14 "In6.Cu" signal)
		(16 "In7.Cu" signal)
		(18 "In8.Cu" signal)
		(2 "B.Cu" signal)
		(9 "F.Adhes" user "F.Adhesive")
		(11 "B.Adhes" user "B.Adhesive")
		(13 "F.Paste" user)
		(15 "B.Paste" user)
		(5 "F.SilkS" user "F.Silkscreen")
		(7 "B.SilkS" user "B.Silkscreen")
		(1 "F.Mask" user)
		(3 "B.Mask" user)
		(17 "Dwgs.User" user "User.Drawings")
		(19 "Cmts.User" user "User.Comments")
		(21 "Eco1.User" user "User.Eco1")
		(23 "Eco2.User" user "User.Eco2")
		(25 "Edge.Cuts" user)
		(27 "Margin" user)
		(31 "F.CrtYd" user "F.Courtyard")
		(29 "B.CrtYd" user "B.Courtyard")
		(35 "F.Fab" user)
		(33 "B.Fab" user)
	)
	(footprint "antmicro-footprints:TP_SMD_0.75mm"
		(layer "B.Cu")
		(at 124.5 104.5)
		(property "Reference" "TP36"
			(at 0.7 -0.47 0)
			(layer "B.SilkS")
			(effects
				(font
					(size 0.7 0.7)
					(thickness 0.15)
				)
				(justify right top mirror)
			)
		)
		(property "Value" "TP_0.75mm_SMD"
			(at 0 -1.2 0)
			(layer "B.Fab")
			(effects
				(font
					(size 0.7 0.7)
					(thickness 0.15)
				)
				(justify right top mirror)
			)
		)
		(property "Description" "SMT test point"
			(at 0 0 0)
			(layer "B.Fab")
			(hide yes)
			(effects
				(font
					(size 1.27 1.27)
					(thickness 0.15)
				)
				(justify mirror)
			)
		)
		(property "MPN" ""
			(at 0 0 180)
			(unlocked yes)
			(layer "B.Fab")
			(hide yes)
			(effects
				(font
					(size 1 1)
					(thickness 0.15)
				)
				(justify mirror)
			)
		)
		(property "Manufacturer" ""
			(at 0 0 180)
			(unlocked yes)
			(layer "B.Fab")
			(hide yes)
			(effects
				(font
					(size 1 1)
					(thickness 0.15)
				)
				(justify mirror)
			)
		)
		(property "Author" "Antmicro"
			(at 0 0 180)
			(unlocked yes)
			(layer "B.Fab")
			(hide yes)
			(effects
				(font
					(size 1 1)
					(thickness 0.15)
				)
				(justify mirror)
			)
		)
		(property "License" "Apache-2.0"
			(at 0 0 180)
			(unlocked yes)
			(layer "B.Fab")
			(hide yes)
			(effects
				(font
					(size 1 1)
					(thickness 0.15)
				)
				(justify mirror)
			)
		)
		(sheetname "/M.2/")
		(sheetfile "m2.kicad_sch")
		(attr exclude_from_pos_files exclude_from_bom)
		(fp_circle
			(center 0 0)
			(end 0.475 0)
			(stroke
				(width 0.05)
				(type default)
			)
			(fill no)
			(layer "B.CrtYd")
		)
		(fp_text user "${REFERENCE}"
			(at -0.4 -2.7 0)
			(layer "B.Fab")
			(effects
				(font
					(size 0.7 0.7)
					(thickness 0.15)
				)
				(justify right top mirror)
			)
		)
		(fp_text user "License: Apache-2.0"
			(at -0.4 -5.101 0)
			(layer "B.Fab")
			(effects
				(font
					(size 0.7 0.7)
					(thickness 0.15)
				)
				(justify right top mirror)
			)
		)
		(fp_text user "Author: Antmicro"
			(at -0.4 -3.901 0)
			(layer "B.Fab")
			(effects
				(font
					(size 0.7 0.7)
					(thickness 0.15)
				)
				(justify right top mirror)
			)
		)
		(pad "1" smd circle
			(at 0 0)
			(size 0.75 0.75)
			(layers "B.Cu" "B.Mask")
			(net 236 "/M.2/~{M2_M_ALERT}")
			(pinfunction "1")
			(pintype "passive")
		)
	)
	(footprint "antmicro-footprints:R_0402_1005Metric"
		(layer "B.Cu")
		(at 223.85 94.85)
		(descr "Resistor SMD 0402")
		(tags "resistor SMD 0402")
		(property "Reference" "R154"
			(at -1.45 1.555 0)
			(layer "B.SilkS")
			(effects
				(font
					(size 0.7 0.7)
					(thickness 0.15)
				)
				(justify right top mirror)
			)
		)
		(property "Value" "R_2M_0402"
			(at -1.011843 -1.772047 0)
			(layer "B.Fab")
			(effects
				(font
					(size 0.7 0.7)
					(thickness 0.15)
				)
				(justify right top mirror)
			)
		)
		(property "Datasheet" "https://www.mouser.com/datasheet/2/447/YAGEO_PYu_RC_Group_51_RoHS_L_12-3313492.pdf"
			(at 0 0 0)
			(layer "B.Fab")
			(hide yes)
			(effects
				(font
					(size 1.27 1.27)
					(thickness 0.15)
				)
				(justify mirror)
			)
		)
		(property "Description" "SMD Chip Resistor, 2 Mohm, ± 1%, 62.5 mW, 0402 [1005 Metric], Thick Film, General Purpose"
			(at 0 0 0)
			(layer "B.Fab")
			(hide yes)
			(effects
				(font
					(size 1.27 1.27)
					(thickness 0.15)
				)
				(justify mirror)
			)
		)
		(property "MPN" "RC0402FR-072ML"
			(at 0 0 180)
			(unlocked yes)
			(layer "B.Fab")
			(hide yes)
			(effects
				(font
					(size 1 1)
					(thickness 0.15)
				)
				(justify mirror)
			)
		)
		(property "Manufacturer" "YAGEO"
			(at 0 0 180)
			(unlocked yes)
			(layer "B.Fab")
			(hide yes)
			(effects
				(font
					(size 1 1)
					(thickness 0.15)
				)
				(justify mirror)
			)
		)
		(property "License" "Apache-2.0"
			(at 0 0 180)
			(unlocked yes)
			(layer "B.Fab")
			(hide yes)
			(effects
				(font
					(size 1 1)
					(thickness 0.15)
				)
				(justify mirror)
			)
		)
		(property "Author" "Antmicro"
			(at 0 0 180)
			(unlocked yes)
			(layer "B.Fab")
			(hide yes)
			(effects
				(font
					(size 1 1)
					(thickness 0.15)
				)
				(justify mirror)
			)
		)
		(property "Val" "2M"
			(at 0 0 180)
			(unlocked yes)
			(layer "B.Fab")
			(hide yes)
			(effects
				(font
					(size 1 1)
					(thickness 0.15)
				)
				(justify mirror)
			)
		)
		(property "Tolerance" "1%"
			(at 0 0 180)
			(unlocked yes)
			(layer "B.Fab")
			(hide yes)
			(effects
				(font
					(size 1 1)
					(thickness 0.15)
				)
				(justify mirror)
			)
		)
		(sheetname "/USB DP Alt mode/")
		(sheetfile "usb_dp.kicad_sch")
		(attr smd)
		(fp_rect
			(start -0.925 0.47)
			(end 0.925 -0.47)
			(stroke
				(width 0.05)
				(type default)
			)
			(fill no)
			(layer "B.CrtYd")
		)
		(fp_rect
			(start -0.5 0.25)
			(end 0.5 -0.25)
			(stroke
				(width 0.15)
				(type solid)
			)
			(fill no)
			(layer "B.Fab")
		)
		(fp_text user "${REFERENCE}"
			(at -0.95 -3.168 0)
			(layer "B.Fab")
			(effects
				(font
					(size 0.7 0.7)
					(thickness 0.15)
				)
				(justify right top mirror)
			)
		)
		(fp_text user "Author: Antmicro"
			(at -0.95 -4.169 0)
			(layer "B.Fab")
			(effects
				(font
					(size 0.7 0.7)
					(thickness 0.15)
				)
				(justify right top mirror)
			)
		)
		(fp_text user "License: Apache-2.0"
			(at -0.95 -5.169 0)
			(layer "B.Fab")
			(effects
				(font
					(size 0.7 0.7)
					(thickness 0.15)
				)
				(justify right top mirror)
			)
		)
		(pad "1" smd roundrect
			(at -0.48 0)
			(size 0.59 0.64)
			(layers "B.Cu" "B.Mask" "B.Paste")
			(roundrect_rratio 0.25)
			(net 821 "/USB DP Alt mode/USBC1_SBU_N")
			(pintype "passive")
		)
		(pad "2" smd roundrect
			(at 0.48 0)
			(size 0.59 0.64)
			(layers "B.Cu" "B.Mask" "B.Paste")
			(roundrect_rratio 0.25)
			(net 1 "GND")
			(pintype "passive")
		)
	)
	(footprint "antmicro-footprints:R_0402_1005Metric"
		(layer "B.Cu")
		(at 209.5 71.5 90)
		(descr "Resistor SMD 0402")
		(tags "resistor SMD 0402")
		(property "Reference" "R176"
			(at 0.89 -0.4 90)
			(layer "B.SilkS")
			(effects
				(font
					(size 0.7 0.7)
					(thickness 0.15)
				)
				(justify right top mirror)
			)
		)
		(property "Value" "R_10k_0402"
			(at -1.011843 -1.772046 90)
			(layer "B.Fab")
			(effects
				(font
					(size 0.7 0.7)
					(thickness 0.15)
				)
				(justify right top mirror)
			)
		)
		(property "Datasheet" "https://www.bourns.com/docs/product-datasheets/cr.pdf"
			(at 0 0 90)
			(layer "B.Fab")
			(hide yes)
			(effects
				(font
					(size 1.27 1.27)
					(thickness 0.15)
				)
				(justify mirror)
			)
		)
		(property "Description" "SMD Chip Resistor, 10 kohm, ± 1%, 62.5 mW, 0402 [1005 Metric], Thick Film, General Purpose"
			(at 0 0 90)
			(layer "B.Fab")
			(hide yes)
			(effects
				(font
					(size 1.27 1.27)
					(thickness 0.15)
				)
				(justify mirror)
			)
		)
		(property "Manufacturer" "Bourns"
			(at 0 0 270)
			(unlocked yes)
			(layer "B.Fab")
			(hide yes)
			(effects
				(font
					(size 1 1)
					(thickness 0.15)
				)
				(justify mirror)
			)
		)
		(property "MPN" "CR0402-FX-1002GLF"
			(at 0 0 270)
			(unlocked yes)
			(layer "B.Fab")
			(hide yes)
			(effects
				(font
					(size 1 1)
					(thickness 0.15)
				)
				(justify mirror)
			)
		)
		(property "Val" "10k"
			(at 0 0 270)
			(unlocked yes)
			(layer "B.Fab")
			(hide yes)
			(effects
				(font
					(size 1 1)
					(thickness 0.15)
				)
				(justify mirror)
			)
		)
		(property "License" "Apache-2.0"
			(at 0 0 270)
			(unlocked yes)
			(layer "B.Fab")
			(hide yes)
			(effects
				(font
					(size 1 1)
					(thickness 0.15)
				)
				(justify mirror)
			)
		)
		(property "Author" "Antmicro"
			(at 0 0 270)
			(unlocked yes)
			(layer "B.Fab")
			(hide yes)
			(effects
				(font
					(size 1 1)
					(thickness 0.15)
				)
				(justify mirror)
			)
		)
		(property "Tolerance" "1%"
			(at 0 0 270)
			(unlocked yes)
			(layer "B.Fab")
			(hide yes)
			(effects
				(font
					(size 1 1)
					(thickness 0.15)
				)
				(justify mirror)
			)
		)
		(sheetname "/CSI/")
		(sheetfile "csi.kicad_sch")
		(attr smd)
		(fp_poly
			(pts
				(xy -0.925 0.47) (xy -0.925 -0.47) (xy 0.925 -0.47) (xy 0.925 0.47)
			)
			(stroke
				(width 0.05)
				(type default)
			)
			(fill no)
			(layer "B.CrtYd")
		)
		(fp_poly
			(pts
				(xy -0.5 0.25) (xy -0.5 -0.25) (xy 0.5 -0.25) (xy 0.5 0.25)
			)
			(stroke
				(width 0.15)
				(type solid)
			)
			(fill no)
			(layer "B.Fab")
		)
		(fp_text user "Author: Antmicro"
			(at -0.95 -4.169 90)
			(layer "B.Fab")
			(effects
				(font
					(size 0.7 0.7)
					(thickness 0.15)
				)
				(justify right top mirror)
			)
		)
		(fp_text user "${REFERENCE}"
			(at -0.95 -3.168 90)
			(layer "B.Fab")
			(effects
				(font
					(size 0.7 0.7)
					(thickness 0.15)
				)
				(justify right top mirror)
			)
		)
		(fp_text user "License: Apache-2.0"
			(at -0.949999 -5.169 90)
			(layer "B.Fab")
			(effects
				(font
					(size 0.7 0.7)
					(thickness 0.15)
				)
				(justify right top mirror)
			)
		)
		(pad "1" smd roundrect
			(at -0.48 0 90)
			(size 0.59 0.64)
			(layers "B.Cu" "B.Mask" "B.Paste")
			(roundrect_rratio 0.25)
			(net 2 "+3V3")
			(pintype "passive")
		)
		(pad "2" smd roundrect
			(at 0.48 0 90)
			(size 0.59 0.64)
			(layers "B.Cu" "B.Mask" "B.Paste")
			(roundrect_rratio 0.25)
			(net 117 "/CSI/CAM_CTRL.CSIB_FLG")
			(pintype "passive")
		)
	)
	(footprint "antmicro-footprints:R_0402_1005Metric"
		(layer "B.Cu")
		(at 173 57.5 -90)
		(descr "Resistor SMD 0402")
		(tags "resistor SMD 0402")
		(property "Reference" "R35"
			(at -3.58 -0.415532 90)
			(layer "B.SilkS")
			(effects
				(font
					(size 0.7 0.7)
					(thickness 0.15)
				)
				(justify left bottom mirror)
			)
		)
		(property "Value" "R_470R_0402"
			(at -1.011843 -1.772047 90)
			(layer "B.Fab")
			(effects
				(font
					(size 0.7 0.7)
					(thickness 0.15)
				)
				(justify left bottom mirror)
			)
		)
		(property "Datasheet" "https://www.bourns.com/docs/product-datasheets/cr.pdf"
			(at 0 0 90)
			(layer "B.Fab")
			(hide yes)
			(effects
				(font
					(size 1.27 1.27)
					(thickness 0.15)
				)
				(justify mirror)
			)
		)
		(property "Description" "SMD Chip Resistor, 470 ohm, ± 1%, 62.5 mW, 0402 [1005 Metric], Thick Film, General Purpose"
			(at 0 0 90)
			(layer "B.Fab")
			(hide yes)
			(effects
				(font
					(size 1.27 1.27)
					(thickness 0.15)
				)
				(justify mirror)
			)
		)
		(property "MPN" "CR0402-FX-4700GLF"
			(at 0 0 90)
			(unlocked yes)
			(layer "B.Fab")
			(hide yes)
			(effects
				(font
					(size 1 1)
					(thickness 0.15)
				)
				(justify mirror)
			)
		)
		(property "Manufacturer" "Bourns"
			(at 0 0 90)
			(unlocked yes)
			(layer "B.Fab")
			(hide yes)
			(effects
				(font
					(size 1 1)
					(thickness 0.15)
				)
				(justify mirror)
			)
		)
		(property "License" "Apache-2.0"
			(at 0 0 90)
			(unlocked yes)
			(layer "B.Fab")
			(hide yes)
			(effects
				(font
					(size 1 1)
					(thickness 0.15)
				)
				(justify mirror)
			)
		)
		(property "Author" "Antmicro"
			(at 0 0 90)
			(unlocked yes)
			(layer "B.Fab")
			(hide yes)
			(effects
				(font
					(size 1 1)
					(thickness 0.15)
				)
				(justify mirror)
			)
		)
		(property "Val" "470R"
			(at 0 0 90)
			(unlocked yes)
			(layer "B.Fab")
			(hide yes)
			(effects
				(font
					(size 1 1)
					(thickness 0.15)
				)
				(justify mirror)
			)
		)
		(property "Tolerance" "1%"
			(at 0 0 90)
			(unlocked yes)
			(layer "B.Fab")
			(hide yes)
			(effects
				(font
					(size 1 1)
					(thickness 0.15)
				)
				(justify mirror)
			)
		)
		(sheetname "/Power/")
		(sheetfile "power.kicad_sch")
		(attr smd)
		(fp_rect
			(start -0.925 0.47)
			(end 0.925 -0.47)
			(stroke
				(width 0.05)
				(type default)
			)
			(fill no)
			(layer "B.CrtYd")
		)
		(fp_rect
			(start -0.5 0.25)
			(end 0.5 -0.25)
			(stroke
				(width 0.15)
				(type solid)
			)
			(fill no)
			(layer "B.Fab")
		)
		(fp_text user "License: Apache-2.0"
			(at -0.95 -5.169 90)
			(layer "B.Fab")
			(effects
				(font
					(size 0.7 0.7)
					(thickness 0.15)
				)
				(justify left bottom mirror)
			)
		)
		(fp_text user "Author: Antmicro"
			(at -0.95 -4.169 90)
			(layer "B.Fab")
			(effects
				(font
					(size 0.7 0.7)
					(thickness 0.15)
				)
				(justify left bottom mirror)
			)
		)
		(fp_text user "${REFERENCE}"
			(at -0.95 -3.168 90)
			(layer "B.Fab")
			(effects
				(font
					(size 0.7 0.7)
					(thickness 0.15)
				)
				(justify left bottom mirror)
			)
		)
		(pad "1" smd roundrect
			(at -0.48 0 270)
			(size 0.59 0.64)
			(layers "B.Cu" "B.Mask" "B.Paste")
			(roundrect_rratio 0.25)
			(net 1127 "Net-(D42-A)")
			(pintype "passive")
		)
		(pad "2" smd roundrect
			(at 0.48 0 270)
			(size 0.59 0.64)
			(layers "B.Cu" "B.Mask" "B.Paste")
			(roundrect_rratio 0.25)
			(net 491 "+5V_AON")
			(pintype "passive")
		)
	)
	(footprint "antmicro-footprints:TP_SMD_0.75mm"
		(layer "B.Cu")
		(at 92.2 72.9)
		(property "Reference" "TP102"
			(at 0.5 -0.4 0)
			(layer "B.SilkS")
			(effects
				(font
					(size 0.7 0.7)
					(thickness 0.15)
				)
				(justify right top mirror)
			)
		)
		(property "Value" "TP_0.75mm_SMD"
			(at 0 -1.2 0)
			(layer "B.Fab")
			(effects
				(font
					(size 0.7 0.7)
					(thickness 0.15)
				)
				(justify right top mirror)
			)
		)
		(property "Description" "SMT test point"
			(at 0 0 0)
			(layer "B.Fab")
			(hide yes)
			(effects
				(font
					(size 1.27 1.27)
					(thickness 0.15)
				)
				(justify mirror)
			)
		)
		(property "MPN" ""
			(at 0 0 180)
			(unlocked yes)
			(layer "B.Fab")
			(hide yes)
			(effects
				(font
					(size 1 1)
					(thickness 0.15)
				)
				(justify mirror)
			)
		)
		(property "Manufacturer" ""
			(at 0 0 180)
			(unlocked yes)
			(layer "B.Fab")
			(hide yes)
			(effects
				(font
					(size 1 1)
					(thickness 0.15)
				)
				(justify mirror)
			)
		)
		(property "Author" "Antmicro"
			(at 0 0 180)
			(unlocked yes)
			(layer "B.Fab")
			(hide yes)
			(effects
				(font
					(size 1 1)
					(thickness 0.15)
				)
				(justify mirror)
			)
		)
		(property "License" "Apache-2.0"
			(at 0 0 180)
			(unlocked yes)
			(layer "B.Fab")
			(hide yes)
			(effects
				(font
					(size 1 1)
					(thickness 0.15)
				)
				(justify mirror)
			)
		)
		(sheetname "/SoM_IO/")
		(sheetfile "som_io.kicad_sch")
		(attr exclude_from_pos_files exclude_from_bom)
		(fp_circle
			(center 0 0)
			(end 0.475 0)
			(stroke
				(width 0.05)
				(type default)
			)
			(fill no)
			(layer "B.CrtYd")
		)
		(fp_text user "Author: Antmicro"
			(at -0.4 -3.901 0)
			(layer "B.Fab")
			(effects
				(font
					(size 0.7 0.7)
					(thickness 0.15)
				)
				(justify right top mirror)
			)
		)
		(fp_text user "License: Apache-2.0"
			(at -0.4 -5.101 0)
			(layer "B.Fab")
			(effects
				(font
					(size 0.7 0.7)
					(thickness 0.15)
				)
				(justify right top mirror)
			)
		)
		(fp_text user "${REFERENCE}"
			(at -0.4 -2.7 0)
			(layer "B.Fab")
			(effects
				(font
					(size 0.7 0.7)
					(thickness 0.15)
				)
				(justify right top mirror)
			)
		)
		(pad "1" smd circle
			(at 0 0)
			(size 0.75 0.75)
			(layers "B.Cu" "B.Mask")
			(net 76 "/SoM_IO/I2S_{M.2}.SDIN")
			(pinfunction "1")
			(pintype "passive")
		)
	)
	(footprint "antmicro-footprints:TP_SMD_0.75mm"
		(layer "B.Cu")
		(at 90.1 67.8 -90)
		(property "Reference" "TP82"
			(at 0.4 -0.3 90)
			(layer "B.SilkS")
			(effects
				(font
					(size 0.7 0.7)
					(thickness 0.15)
				)
				(justify left bottom mirror)
			)
		)
		(property "Value" "TP_0.75mm_SMD"
			(at 0 -1.2 90)
			(layer "B.Fab")
			(effects
				(font
					(size 0.7 0.7)
					(thickness 0.15)
				)
				(justify left bottom mirror)
			)
		)
		(property "Description" "SMT test point"
			(at 0 0 90)
			(layer "B.Fab")
			(hide yes)
			(effects
				(font
					(size 1.27 1.27)
					(thickness 0.15)
				)
				(justify mirror)
			)
		)
		(property "MPN" ""
			(at 0 0 90)
			(unlocked yes)
			(layer "B.Fab")
			(hide yes)
			(effects
				(font
					(size 1 1)
					(thickness 0.15)
				)
				(justify mirror)
			)
		)
		(property "Manufacturer" ""
			(at 0 0 90)
			(unlocked yes)
			(layer "B.Fab")
			(hide yes)
			(effects
				(font
					(size 1 1)
					(thickness 0.15)
				)
				(justify mirror)
			)
		)
		(property "Author" "Antmicro"
			(at 0 0 90)
			(unlocked yes)
			(layer "B.Fab")
			(hide yes)
			(effects
				(font
					(size 1 1)
					(thickness 0.15)
				)
				(justify mirror)
			)
		)
		(property "License" "Apache-2.0"
			(at 0 0 90)
			(unlocked yes)
			(layer "B.Fab")
			(hide yes)
			(effects
				(font
					(size 1 1)
					(thickness 0.15)
				)
				(justify mirror)
			)
		)
		(sheetname "/SoM_Power/")
		(sheetfile "som_power.kicad_sch")
		(attr exclude_from_pos_files exclude_from_bom)
		(fp_circle
			(center 0 0)
			(end 0.475 0)
			(stroke
				(width 0.05)
				(type default)
			)
			(fill no)
			(layer "B.CrtYd")
		)
		(fp_text user "Author: Antmicro"
			(at -0.4 -3.901 90)
			(layer "B.Fab")
			(effects
				(font
					(size 0.7 0.7)
					(thickness 0.15)
				)
				(justify left bottom mirror)
			)
		)
		(fp_text user "License: Apache-2.0"
			(at -0.4 -5.101 90)
			(layer "B.Fab")
			(effects
				(font
					(size 0.7 0.7)
					(thickness 0.15)
				)
				(justify left bottom mirror)
			)
		)
		(fp_text user "${REFERENCE}"
			(at -0.4 -2.7 90)
			(layer "B.Fab")
			(effects
				(font
					(size 0.7 0.7)
					(thickness 0.15)
				)
				(justify left bottom mirror)
			)
		)
		(pad "1" smd circle
			(at 0 0 270)
			(size 0.75 0.75)
			(layers "B.Cu" "B.Mask")
			(net 605 "/SoM_Power/~{MODULE_SHDN}")
			(pinfunction "1")
			(pintype "passive")
		)
	)
)
